(kicad_pcb
	(version 20260206)
	(generator "pcbnew")
	(generator_version "10.0")
	(general
		(thickness 1.6)
		(legacy_teardrops no)
	)
	(paper "A4")
	(title_block
		(title "01162023_DA0F0TEBIF0_F0T_Expander_BD_F_brd_V02_OCP.brd")
		(comment 1 "Grand Teton / footprints 7963-7970 of 9728")
	)
	(layers
		(0 "F.Cu" signal "TOP")
		(4 "In1.Cu" signal "GND")
		(6 "In2.Cu" signal "VCC")
		(8 "In3.Cu" signal "VCC1")
		(10 "In4.Cu" signal "GND1")
		(12 "In5.Cu" signal "IN1")
		(14 "In6.Cu" signal "GND2")
		(16 "In7.Cu" signal "IN2")
		(18 "In8.Cu" signal "GND3")
		(20 "In9.Cu" signal "IN3")
		(22 "In10.Cu" signal "GND4")
		(24 "In11.Cu" signal "IN4")
		(26 "In12.Cu" signal "GND5")
		(28 "In13.Cu" signal "IN5")
		(30 "In14.Cu" signal "GND6")
		(32 "In15.Cu" signal "IN6")
		(34 "In16.Cu" signal "GND7")
		(2 "B.Cu" signal "BOTTOM")
		(9 "F.Adhes" user "F.Adhesive")
		(11 "B.Adhes" user "B.Adhesive")
		(13 "F.Paste" user "Package Geometry/Pastemask Top")
		(15 "B.Paste" user "Package Geometry/Pastemask Bottom")
		(5 "F.SilkS" user "Ref Des/Silkscreen Top")
		(7 "B.SilkS" user "Ref Des/Silkscreen Bottom")
		(1 "F.Mask" user "Board Geometry/Soldermask Top")
		(3 "B.Mask" user "Board Geometry/Soldermask Bottom")
		(17 "Dwgs.User" user "User.Drawings")
		(19 "Cmts.User" user "User.Comments")
		(21 "Eco1.User" user "User.Eco1")
		(23 "Eco2.User" user "User.Eco2")
		(25 "Edge.Cuts" user "Board Geometry/Outline")
		(27 "Margin" user)
		(31 "F.CrtYd" user "Package Geometry/Place Bound Top")
		(29 "B.CrtYd" user "Package Geometry/Place Bound Bottom")
		(35 "F.Fab" user "Ref Des/Assembly Top")
		(33 "B.Fab" user "Ref Des/Assembly Bottom")
	)
	(footprint ""
		(layer "B.Cu")
		(at 305.109626 -239.976406 90)
		(property "Reference" "R4107"
			(at 0 0 90)
			(layer "B.SilkS")
			(hide yes)
			(effects
				(font
					(size 1.27 1.27)
				)
				(justify mirror)
			)
		)
		(property "Value" ""
			(at 0 0 90)
			(layer "B.Fab")
			(effects
				(font
					(size 1.27 1.27)
				)
				(justify mirror)
			)
		)
		(duplicate_pad_numbers_are_jumpers no)
		(fp_line
			(start 0.7874 -0.4064)
			(end -0.7874 -0.4064)
			(stroke
				(width 0.1524)
				(type default)
			)
			(layer "B.SilkS")
		)
		(fp_line
			(start -0.7874 -0.4064)
			(end -0.7874 0.4064)
			(stroke
				(width 0.1524)
				(type default)
			)
			(layer "B.SilkS")
		)
		(fp_line
			(start 0.7874 0.4064)
			(end 0.7874 -0.4064)
			(stroke
				(width 0.1524)
				(type default)
			)
			(layer "B.SilkS")
		)
		(fp_line
			(start -0.7874 0.4064)
			(end 0.7874 0.4064)
			(stroke
				(width 0.1524)
				(type default)
			)
			(layer "B.SilkS")
		)
		(fp_line
			(start 0.67945 -0.305054)
			(end 0.12065 -0.305054)
			(stroke
				(width 0.1)
				(type default)
			)
			(layer "B.Fab")
		)
		(fp_line
			(start 0.12065 -0.305054)
			(end 0.12065 -0.2794)
			(stroke
				(width 0.1)
				(type default)
			)
			(layer "B.Fab")
		)
		(fp_line
			(start -0.12065 -0.3048)
			(end -0.67945 -0.3048)
			(stroke
				(width 0.1)
				(type default)
			)
			(layer "B.Fab")
		)
		(fp_line
			(start -0.67945 -0.3048)
			(end -0.67945 0.3048)
			(stroke
				(width 0.1)
				(type default)
			)
			(layer "B.Fab")
		)
		(fp_line
			(start 0.12065 -0.2794)
			(end -0.12065 -0.2794)
			(stroke
				(width 0.1)
				(type default)
			)
			(layer "B.Fab")
		)
		(fp_line
			(start -0.12065 -0.2794)
			(end -0.12065 -0.3048)
			(stroke
				(width 0.1)
				(type default)
			)
			(layer "B.Fab")
		)
		(fp_line
			(start 0.12065 0.2794)
			(end 0.12065 0.3048)
			(stroke
				(width 0.1)
				(type default)
			)
			(layer "B.Fab")
		)
		(fp_line
			(start -0.120396 0.2794)
			(end 0.12065 0.2794)
			(stroke
				(width 0.1)
				(type default)
			)
			(layer "B.Fab")
		)
		(fp_line
			(start 0.67945 0.3048)
			(end 0.67945 -0.305054)
			(stroke
				(width 0.1)
				(type default)
			)
			(layer "B.Fab")
		)
		(fp_line
			(start 0.12065 0.3048)
			(end 0.67945 0.3048)
			(stroke
				(width 0.1)
				(type default)
			)
			(layer "B.Fab")
		)
		(fp_line
			(start -0.120396 0.3048)
			(end -0.120396 0.2794)
			(stroke
				(width 0.1)
				(type default)
			)
			(layer "B.Fab")
		)
		(fp_line
			(start -0.67945 0.3048)
			(end -0.120396 0.3048)
			(stroke
				(width 0.1)
				(type default)
			)
			(layer "B.Fab")
		)
		(pad "1" smd circle
			(at 0.40005 0 270)
			(size 0 0)
			(layers "B.Cu" "B.Mask" "B.Paste")
			(net "SMB_MB_BMC_ISO_SCL")
		)
		(pad "2" smd circle
			(at -0.40005 0 270)
			(size 0 0)
			(layers "B.Cu" "B.Mask" "B.Paste")
			(net "SMB_MB_R_SCL")
		)
	)
	(footprint ""
		(layer "B.Cu")
		(at 169.730166 -295.221914)
		(property "Reference" "C1356"
			(at 0 0 0)
			(layer "B.SilkS")
			(hide yes)
			(effects
				(font
					(size 1.27 1.27)
				)
				(justify mirror)
			)
		)
		(property "Value" ""
			(at 0 0 0)
			(layer "B.Fab")
			(effects
				(font
					(size 1.27 1.27)
				)
				(justify mirror)
			)
		)
		(duplicate_pad_numbers_are_jumpers no)
		(fp_line
			(start -1.2954 -0.5842)
			(end -1.2954 0.5842)
			(stroke
				(width 0.1524)
				(type default)
			)
			(layer "B.SilkS")
		)
		(fp_line
			(start -1.2954 0.5842)
			(end 1.2954 0.5842)
			(stroke
				(width 0.1524)
				(type default)
			)
			(layer "B.SilkS")
		)
		(fp_line
			(start 1.2954 -0.5842)
			(end -1.2954 -0.5842)
			(stroke
				(width 0.1524)
				(type default)
			)
			(layer "B.SilkS")
		)
		(fp_line
			(start 1.2954 0.5842)
			(end 1.2954 -0.5842)
			(stroke
				(width 0.1524)
				(type default)
			)
			(layer "B.SilkS")
		)
		(fp_line
			(start -1.1938 -0.4064)
			(end -1.1938 0.4064)
			(stroke
				(width 0.1)
				(type default)
			)
			(layer "B.Fab")
		)
		(fp_line
			(start -1.1938 0.4064)
			(end -0.8636 0.4064)
			(stroke
				(width 0.1)
				(type default)
			)
			(layer "B.Fab")
		)
		(fp_line
			(start -0.8636 -0.4572)
			(end -0.8636 -0.4064)
			(stroke
				(width 0.1)
				(type default)
			)
			(layer "B.Fab")
		)
		(fp_line
			(start -0.8636 -0.4064)
			(end -1.1938 -0.4064)
			(stroke
				(width 0.1)
				(type default)
			)
			(layer "B.Fab")
		)
		(fp_line
			(start -0.8636 0.4064)
			(end -0.8636 0.4572)
			(stroke
				(width 0.1)
				(type default)
			)
			(layer "B.Fab")
		)
		(fp_line
			(start -0.8636 0.4572)
			(end 0.8636 0.4572)
			(stroke
				(width 0.1)
				(type default)
			)
			(layer "B.Fab")
		)
		(fp_line
			(start 0.8636 -0.4572)
			(end -0.8636 -0.4572)
			(stroke
				(width 0.1)
				(type default)
			)
			(layer "B.Fab")
		)
		(fp_line
			(start 0.8636 -0.4064)
			(end 0.8636 -0.4572)
			(stroke
				(width 0.1)
				(type default)
			)
			(layer "B.Fab")
		)
		(fp_line
			(start 0.8636 0.4064)
			(end 1.1938 0.4064)
			(stroke
				(width 0.1)
				(type default)
			)
			(layer "B.Fab")
		)
		(fp_line
			(start 0.8636 0.4572)
			(end 0.8636 0.4064)
			(stroke
				(width 0.1)
				(type default)
			)
			(layer "B.Fab")
		)
		(fp_line
			(start 1.1938 -0.4064)
			(end 0.8636 -0.4064)
			(stroke
				(width 0.1)
				(type default)
			)
			(layer "B.Fab")
		)
		(fp_line
			(start 1.1938 0.4064)
			(end 1.1938 -0.4064)
			(stroke
				(width 0.1)
				(type default)
			)
			(layer "B.Fab")
		)
		(pad "1" smd rect
			(at 0.7366 0 270)
			(size 0.7112 0.8128)
			(layers "B.Cu" "B.Mask" "B.Paste")
			(net "P0V8_PEX1")
		)
		(pad "2" smd rect
			(at -0.7366 0 270)
			(size 0.7112 0.8128)
			(layers "B.Cu" "B.Mask" "B.Paste")
			(net "GND")
		)
	)
	(footprint ""
		(layer "B.Cu")
		(at 411.275022 -286.399732 90)
		(property "Reference" "C3503"
			(at 0 0 90)
			(layer "B.SilkS")
			(hide yes)
			(effects
				(font
					(size 1.27 1.27)
				)
				(justify mirror)
			)
		)
		(property "Value" ""
			(at 0 0 90)
			(layer "B.Fab")
			(effects
				(font
					(size 1.27 1.27)
				)
				(justify mirror)
			)
		)
		(duplicate_pad_numbers_are_jumpers no)
		(fp_line
			(start 0.299974 -0.150114)
			(end -0.299974 -0.150114)
			(stroke
				(width 0.1)
				(type default)
			)
			(layer "B.Fab")
		)
		(fp_line
			(start -0.299974 -0.150114)
			(end -0.299974 0.150114)
			(stroke
				(width 0.1)
				(type default)
			)
			(layer "B.Fab")
		)
		(fp_line
			(start 0.299974 0.150114)
			(end 0.299974 -0.150114)
			(stroke
				(width 0.1)
				(type default)
			)
			(layer "B.Fab")
		)
		(fp_line
			(start -0.299974 0.150114)
			(end 0.299974 0.150114)
			(stroke
				(width 0.1)
				(type default)
			)
			(layer "B.Fab")
		)
		(pad "1" smd rect
			(at 0.2667 0 270)
			(size 0.3048 0.381)
			(layers "B.Cu" "B.Mask" "B.Paste")
			(net "P1V25_SERDES_VDDPLL_PEX3")
		)
		(pad "2" smd rect
			(at -0.2667 0 270)
			(size 0.3048 0.381)
			(layers "B.Cu" "B.Mask" "B.Paste")
			(net "GND")
		)
	)
	(footprint ""
		(layer "B.Cu")
		(at 417.241482 -286.874966)
		(property "Reference" "C3520"
			(at 0 0 0)
			(layer "B.SilkS")
			(hide yes)
			(effects
				(font
					(size 1.27 1.27)
				)
				(justify mirror)
			)
		)
		(property "Value" ""
			(at 0 0 0)
			(layer "B.Fab")
			(effects
				(font
					(size 1.27 1.27)
				)
				(justify mirror)
			)
		)
		(duplicate_pad_numbers_are_jumpers no)
		(fp_line
			(start -0.299974 -0.150114)
			(end -0.299974 0.150114)
			(stroke
				(width 0.1)
				(type default)
			)
			(layer "B.Fab")
		)
		(fp_line
			(start -0.299974 0.150114)
			(end 0.299974 0.150114)
			(stroke
				(width 0.1)
				(type default)
			)
			(layer "B.Fab")
		)
		(fp_line
			(start 0.299974 -0.150114)
			(end -0.299974 -0.150114)
			(stroke
				(width 0.1)
				(type default)
			)
			(layer "B.Fab")
		)
		(fp_line
			(start 0.299974 0.150114)
			(end 0.299974 -0.150114)
			(stroke
				(width 0.1)
				(type default)
			)
			(layer "B.Fab")
		)
		(pad "1" smd rect
			(at 0.2667 0 180)
			(size 0.3048 0.381)
			(layers "B.Cu" "B.Mask" "B.Paste")
			(net "P1V8_VDDA_PEX3")
		)
		(pad "2" smd rect
			(at -0.2667 0 180)
			(size 0.3048 0.381)
			(layers "B.Cu" "B.Mask" "B.Paste")
			(net "GND")
		)
	)
	(footprint ""
		(layer "B.Cu")
		(at 324.540118 -229.913942)
		(property "Reference" "R5892"
			(at 0 0 0)
			(layer "B.SilkS")
			(hide yes)
			(effects
				(font
					(size 1.27 1.27)
				)
				(justify mirror)
			)
		)
		(property "Value" ""
			(at 0 0 0)
			(layer "B.Fab")
			(effects
				(font
					(size 1.27 1.27)
				)
				(justify mirror)
			)
		)
		(duplicate_pad_numbers_are_jumpers no)
		(fp_line
			(start -0.7874 -0.4064)
			(end -0.7874 0.4064)
			(stroke
				(width 0.1524)
				(type default)
			)
			(layer "B.SilkS")
		)
		(fp_line
			(start -0.7874 0.4064)
			(end 0.7874 0.4064)
			(stroke
				(width 0.1524)
				(type default)
			)
			(layer "B.SilkS")
		)
		(fp_line
			(start 0.7874 -0.4064)
			(end -0.7874 -0.4064)
			(stroke
				(width 0.1524)
				(type default)
			)
			(layer "B.SilkS")
		)
		(fp_line
			(start 0.7874 0.4064)
			(end 0.7874 -0.4064)
			(stroke
				(width 0.1524)
				(type default)
			)
			(layer "B.SilkS")
		)
		(fp_line
			(start -0.67945 -0.3048)
			(end -0.67945 0.3048)
			(stroke
				(width 0.1)
				(type default)
			)
			(layer "B.Fab")
		)
		(fp_line
			(start -0.67945 0.3048)
			(end -0.120396 0.3048)
			(stroke
				(width 0.1)
				(type default)
			)
			(layer "B.Fab")
		)
		(fp_line
			(start -0.12065 -0.3048)
			(end -0.67945 -0.3048)
			(stroke
				(width 0.1)
				(type default)
			)
			(layer "B.Fab")
		)
		(fp_line
			(start -0.12065 -0.2794)
			(end -0.12065 -0.3048)
			(stroke
				(width 0.1)
				(type default)
			)
			(layer "B.Fab")
		)
		(fp_line
			(start -0.120396 0.2794)
			(end 0.12065 0.2794)
			(stroke
				(width 0.1)
				(type default)
			)
			(layer "B.Fab")
		)
		(fp_line
			(start -0.120396 0.3048)
			(end -0.120396 0.2794)
			(stroke
				(width 0.1)
				(type default)
			)
			(layer "B.Fab")
		)
		(fp_line
			(start 0.12065 -0.305054)
			(end 0.12065 -0.2794)
			(stroke
				(width 0.1)
				(type default)
			)
			(layer "B.Fab")
		)
		(fp_line
			(start 0.12065 -0.2794)
			(end -0.12065 -0.2794)
			(stroke
				(width 0.1)
				(type default)
			)
			(layer "B.Fab")
		)
		(fp_line
			(start 0.12065 0.2794)
			(end 0.12065 0.3048)
			(stroke
				(width 0.1)
				(type default)
			)
			(layer "B.Fab")
		)
		(fp_line
			(start 0.12065 0.3048)
			(end 0.67945 0.3048)
			(stroke
				(width 0.1)
				(type default)
			)
			(layer "B.Fab")
		)
		(fp_line
			(start 0.67945 -0.305054)
			(end 0.12065 -0.305054)
			(stroke
				(width 0.1)
				(type default)
			)
			(layer "B.Fab")
		)
		(fp_line
			(start 0.67945 0.3048)
			(end 0.67945 -0.305054)
			(stroke
				(width 0.1)
				(type default)
			)
			(layer "B.Fab")
		)
		(pad "1" smd circle
			(at 0.40005 0 180)
			(size 0 0)
			(layers "B.Cu" "B.Mask" "B.Paste")
			(net "P3V3_LED")
		)
		(pad "2" smd circle
			(at -0.40005 0 180)
			(size 0 0)
			(layers "B.Cu" "B.Mask" "B.Paste")
			(net "FPGA_DEBUG_LED")
		)
	)
	(footprint ""
		(layer "B.Cu")
		(at 260.58368 -80.982312 -90)
		(property "Reference" "C2632"
			(at 0 0 90)
			(layer "B.SilkS")
			(hide yes)
			(effects
				(font
					(size 1.27 1.27)
				)
				(justify mirror)
			)
		)
		(property "Value" ""
			(at 0 0 90)
			(layer "B.Fab")
			(effects
				(font
					(size 1.27 1.27)
				)
				(justify mirror)
			)
		)
		(duplicate_pad_numbers_are_jumpers no)
		(fp_line
			(start -0.7874 0.4064)
			(end 0.7874 0.4064)
			(stroke
				(width 0.1524)
				(type default)
			)
			(layer "B.SilkS")
		)
		(fp_line
			(start 0.7874 0.4064)
			(end 0.7874 -0.4064)
			(stroke
				(width 0.1524)
				(type default)
			)
			(layer "B.SilkS")
		)
		(fp_line
			(start -0.7874 -0.4064)
			(end -0.7874 0.4064)
			(stroke
				(width 0.1524)
				(type default)
			)
			(layer "B.SilkS")
		)
		(fp_line
			(start 0.7874 -0.4064)
			(end -0.7874 -0.4064)
			(stroke
				(width 0.1524)
				(type default)
			)
			(layer "B.SilkS")
		)
		(fp_line
			(start -0.67945 0.3048)
			(end -0.120396 0.3048)
			(stroke
				(width 0.1)
				(type default)
			)
			(layer "B.Fab")
		)
		(fp_line
			(start -0.120396 0.3048)
			(end -0.120396 0.2794)
			(stroke
				(width 0.1)
				(type default)
			)
			(layer "B.Fab")
		)
		(fp_line
			(start 0.12065 0.3048)
			(end 0.67945 0.3048)
			(stroke
				(width 0.1)
				(type default)
			)
			(layer "B.Fab")
		)
		(fp_line
			(start 0.67945 0.3048)
			(end 0.67945 -0.305054)
			(stroke
				(width 0.1)
				(type default)
			)
			(layer "B.Fab")
		)
		(fp_line
			(start -0.120396 0.2794)
			(end 0.12065 0.2794)
			(stroke
				(width 0.1)
				(type default)
			)
			(layer "B.Fab")
		)
		(fp_line
			(start 0.12065 0.2794)
			(end 0.12065 0.3048)
			(stroke
				(width 0.1)
				(type default)
			)
			(layer "B.Fab")
		)
		(fp_line
			(start -0.12065 -0.2794)
			(end -0.12065 -0.3048)
			(stroke
				(width 0.1)
				(type default)
			)
			(layer "B.Fab")
		)
		(fp_line
			(start 0.12065 -0.2794)
			(end -0.12065 -0.2794)
			(stroke
				(width 0.1)
				(type default)
			)
			(layer "B.Fab")
		)
		(fp_line
			(start -0.67945 -0.3048)
			(end -0.67945 0.3048)
			(stroke
				(width 0.1)
				(type default)
			)
			(layer "B.Fab")
		)
		(fp_line
			(start -0.12065 -0.3048)
			(end -0.67945 -0.3048)
			(stroke
				(width 0.1)
				(type default)
			)
			(layer "B.Fab")
		)
		(fp_line
			(start 0.12065 -0.305054)
			(end 0.12065 -0.2794)
			(stroke
				(width 0.1)
				(type default)
			)
			(layer "B.Fab")
		)
		(fp_line
			(start 0.67945 -0.305054)
			(end 0.12065 -0.305054)
			(stroke
				(width 0.1)
				(type default)
			)
			(layer "B.Fab")
		)
		(pad "1" smd circle
			(at 0.40005 0 90)
			(size 0 0)
			(layers "B.Cu" "B.Mask" "B.Paste")
			(net "P3V3_CLK_GEN_VDD_CK440")
		)
		(pad "2" smd circle
			(at -0.40005 0 90)
			(size 0 0)
			(layers "B.Cu" "B.Mask" "B.Paste")
			(net "GND")
		)
	)
	(footprint ""
		(layer "B.Cu")
		(at 169.099992 -288.299906 90)
		(property "Reference" "C3115"
			(at 0 0 90)
			(layer "B.SilkS")
			(hide yes)
			(effects
				(font
					(size 1.27 1.27)
				)
				(justify mirror)
			)
		)
		(property "Value" ""
			(at 0 0 90)
			(layer "B.Fab")
			(effects
				(font
					(size 1.27 1.27)
				)
				(justify mirror)
			)
		)
		(duplicate_pad_numbers_are_jumpers no)
		(fp_line
			(start 0.299974 -0.150114)
			(end -0.299974 -0.150114)
			(stroke
				(width 0.1)
				(type default)
			)
			(layer "B.Fab")
		)
		(fp_line
			(start -0.299974 -0.150114)
			(end -0.299974 0.150114)
			(stroke
				(width 0.1)
				(type default)
			)
			(layer "B.Fab")
		)
		(fp_line
			(start 0.299974 0.150114)
			(end 0.299974 -0.150114)
			(stroke
				(width 0.1)
				(type default)
			)
			(layer "B.Fab")
		)
		(fp_line
			(start -0.299974 0.150114)
			(end 0.299974 0.150114)
			(stroke
				(width 0.1)
				(type default)
			)
			(layer "B.Fab")
		)
		(pad "1" smd rect
			(at 0.2667 0 270)
			(size 0.3048 0.381)
			(layers "B.Cu" "B.Mask" "B.Paste")
			(net "P1V25_PEX1")
		)
		(pad "2" smd rect
			(at -0.2667 0 270)
			(size 0.3048 0.381)
			(layers "B.Cu" "B.Mask" "B.Paste")
			(net "GND")
		)
	)
	(footprint ""
		(layer "B.Cu")
		(at 413.174942 -297.79976 -90)
		(property "Reference" "C1912"
			(at 0 0 90)
			(layer "B.SilkS")
			(hide yes)
			(effects
				(font
					(size 1.27 1.27)
				)
				(justify mirror)
			)
		)
		(property "Value" ""
			(at 0 0 90)
			(layer "B.Fab")
			(effects
				(font
					(size 1.27 1.27)
				)
				(justify mirror)
			)
		)
		(duplicate_pad_numbers_are_jumpers no)
		(fp_line
			(start -0.299974 0.150114)
			(end 0.299974 0.150114)
			(stroke
				(width 0.1)
				(type default)
			)
			(layer "B.Fab")
		)
		(fp_line
			(start 0.299974 0.150114)
			(end 0.299974 -0.150114)
			(stroke
				(width 0.1)
				(type default)
			)
			(layer "B.Fab")
		)
		(fp_line
			(start -0.299974 -0.150114)
			(end -0.299974 0.150114)
			(stroke
				(width 0.1)
				(type default)
			)
			(layer "B.Fab")
		)
		(fp_line
			(start 0.299974 -0.150114)
			(end -0.299974 -0.150114)
			(stroke
				(width 0.1)
				(type default)
			)
			(layer "B.Fab")
		)
		(pad "1" smd rect
			(at 0.2667 0 90)
			(size 0.3048 0.381)
			(layers "B.Cu" "B.Mask" "B.Paste")
			(net "P0V8_PEX3")
		)
		(pad "2" smd rect
			(at -0.2667 0 90)
			(size 0.3048 0.381)
			(layers "B.Cu" "B.Mask" "B.Paste")
			(net "GND")
		)
	)
)
